# S9S_MB_2U (Grand Teton) — schematic netlist excerpt (pin names and nets, part order shuffled) for the footprints in the layout excerpt that follows; sources: Cadence DE-HDL packaged netlist, KiCad conversion of 03242023_DA0F0TMBIJ0_F0T_Motherboard_J_brd_V01_OCP.brd

PR1746  Q_RES  8.87K 1% EMPTY  pkg 0402LF  page 297 : A = PVCCD_HV_CPU1_LSET1 ; B = GND
R3307  Q_RES  0 5% CHIP  pkg 0402LF  page 165 : A = OCP_SFF_RBT_ARB_IN_MUX2 ; B = OCP_SFF_RBT_ARB_IN_MUX2_R

(kicad_pcb
	(version 20260206)
	(generator "pcbnew")
	(generator_version "10.0")
	(general
		(thickness 1.6)
		(legacy_teardrops no)
	)
	(paper "A4")
	(title_block
		(title "03242023_DA0F0TMBIJ0_F0T_Motherboard_J_brd_V01_OCP.brd")
		(comment 1 "Grand Teton / footprints 3167-3168 of 6105")
	)
	(layers
		(0 "F.Cu" signal "TOP")
		(4 "In1.Cu" signal "GND")
		(6 "In2.Cu" signal "IN1")
		(8 "In3.Cu" signal "GND1")
		(10 "In4.Cu" signal "IN2")
		(12 "In5.Cu" signal "GND2")
		(14 "In6.Cu" signal "IN3")
		(16 "In7.Cu" signal "GND3")
		(18 "In8.Cu" signal "VCC")
		(20 "In9.Cu" signal "VCC1")
		(22 "In10.Cu" signal "GND4")
		(24 "In11.Cu" signal "IN4")
		(26 "In12.Cu" signal "GND5")
		(28 "In13.Cu" signal "IN5")
		(30 "In14.Cu" signal "GND6")
		(32 "In15.Cu" signal "IN6")
		(34 "In16.Cu" signal "GND7")
		(2 "B.Cu" signal "BOTTOM")
		(9 "F.Adhes" user "F.Adhesive")
		(11 "B.Adhes" user "B.Adhesive")
		(13 "F.Paste" user "Package Geometry/Pastemask Top")
		(15 "B.Paste" user "Package Geometry/Pastemask Bottom")
		(5 "F.SilkS" user "Ref Des/Silkscreen Top")
		(7 "B.SilkS" user "Ref Des/Silkscreen Bottom")
		(1 "F.Mask" user "Board Geometry/Soldermask Top")
		(3 "B.Mask" user "Board Geometry/Soldermask Bottom")
		(17 "Dwgs.User" user "User.Drawings")
		(19 "Cmts.User" user "User.Comments")
		(21 "Eco1.User" user "User.Eco1")
		(23 "Eco2.User" user "User.Eco2")
		(25 "Edge.Cuts" user "Board Geometry/Outline")
		(27 "Margin" user)
		(31 "F.CrtYd" user "Package Geometry/Place Bound Top")
		(29 "B.CrtYd" user "Package Geometry/Place Bound Bottom")
		(35 "F.Fab" user "Ref Des/Assembly Top")
		(33 "B.Fab" user "Ref Des/Assembly Bottom")
	)
	(footprint ""
		(layer "F.Cu")
		(at 140.70838 -32.458152 180)
		(property "Reference" "R3307"
			(at 0 0 180)
			(layer "F.SilkS")
			(hide yes)
			(effects
				(font
					(size 1.27 1.27)
				)
			)
		)
		(property "Value" ""
			(at 0 0 180)
			(layer "F.Fab")
			(effects
				(font
					(size 1.27 1.27)
				)
			)
		)
		(duplicate_pad_numbers_are_jumpers no)
		(fp_line
			(start 0.7874 0.4064)
			(end -0.7874 0.4064)
			(stroke
				(width 0.1524)
				(type default)
			)
			(layer "F.SilkS")
		)
		(fp_line
			(start 0.7874 -0.4064)
			(end 0.7874 0.4064)
			(stroke
				(width 0.1524)
				(type default)
			)
			(layer "F.SilkS")
		)
		(fp_line
			(start -0.7874 0.4064)
			(end -0.7874 -0.4064)
			(stroke
				(width 0.1524)
				(type default)
			)
			(layer "F.SilkS")
		)
		(fp_line
			(start -0.7874 -0.4064)
			(end 0.7874 -0.4064)
			(stroke
				(width 0.1524)
				(type default)
			)
			(layer "F.SilkS")
		)
		(fp_line
			(start 0.67945 0.3048)
			(end 0.120396 0.3048)
			(stroke
				(width 0.1)
				(type default)
			)
			(layer "F.Fab")
		)
		(fp_line
			(start 0.67945 -0.3048)
			(end 0.67945 0.3048)
			(stroke
				(width 0.1)
				(type default)
			)
			(layer "F.Fab")
		)
		(fp_line
			(start 0.12065 -0.2794)
			(end 0.12065 -0.3048)
			(stroke
				(width 0.1)
				(type default)
			)
			(layer "F.Fab")
		)
		(fp_line
			(start 0.12065 -0.3048)
			(end 0.67945 -0.3048)
			(stroke
				(width 0.1)
				(type default)
			)
			(layer "F.Fab")
		)
		(fp_line
			(start 0.120396 0.3048)
			(end 0.120396 0.2794)
			(stroke
				(width 0.1)
				(type default)
			)
			(layer "F.Fab")
		)
		(fp_line
			(start 0.120396 0.2794)
			(end -0.12065 0.2794)
			(stroke
				(width 0.1)
				(type default)
			)
			(layer "F.Fab")
		)
		(fp_line
			(start -0.12065 0.3048)
			(end -0.67945 0.3048)
			(stroke
				(width 0.1)
				(type default)
			)
			(layer "F.Fab")
		)
		(fp_line
			(start -0.12065 0.2794)
			(end -0.12065 0.3048)
			(stroke
				(width 0.1)
				(type default)
			)
			(layer "F.Fab")
		)
		(fp_line
			(start -0.12065 -0.2794)
			(end 0.12065 -0.2794)
			(stroke
				(width 0.1)
				(type default)
			)
			(layer "F.Fab")
		)
		(fp_line
			(start -0.12065 -0.305054)
			(end -0.12065 -0.2794)
			(stroke
				(width 0.1)
				(type default)
			)
			(layer "F.Fab")
		)
		(fp_line
			(start -0.67945 0.3048)
			(end -0.67945 -0.305054)
			(stroke
				(width 0.1)
				(type default)
			)
			(layer "F.Fab")
		)
		(fp_line
			(start -0.67945 -0.305054)
			(end -0.12065 -0.305054)
			(stroke
				(width 0.1)
				(type default)
			)
			(layer "F.Fab")
		)
		(pad "1" smd circle
			(at -0.40005 0 180)
			(size 0 0)
			(layers "F.Cu" "F.Mask" "F.Paste")
			(net "OCP_SFF_RBT_ARB_IN_MUX2")
		)
		(pad "2" smd circle
			(at 0.40005 0 180)
			(size 0 0)
			(layers "F.Cu" "F.Mask" "F.Paste")
			(net "OCP_SFF_RBT_ARB_IN_MUX2_R")
		)
	)
	(footprint ""
		(layer "F.Cu")
		(at 49.755552 -163.822634 90)
		(property "Reference" "PR1746"
			(at 0 0 90)
			(layer "F.SilkS")
			(hide yes)
			(effects
				(font
					(size 1.27 1.27)
				)
			)
		)
		(property "Value" ""
			(at 0 0 90)
			(layer "F.Fab")
			(effects
				(font
					(size 1.27 1.27)
				)
			)
		)
		(duplicate_pad_numbers_are_jumpers no)
		(fp_line
			(start 0.7874 -0.4064)
			(end 0.7874 0.4064)
			(stroke
				(width 0.1524)
				(type default)
			)
			(layer "F.SilkS")
		)
		(fp_line
			(start -0.7874 -0.4064)
			(end 0.7874 -0.4064)
			(stroke
				(width 0.1524)
				(type default)
			)
			(layer "F.SilkS")
		)
		(fp_line
			(start 0.7874 0.4064)
			(end -0.7874 0.4064)
			(stroke
				(width 0.1524)
				(type default)
			)
			(layer "F.SilkS")
		)
		(fp_line
			(start -0.7874 0.4064)
			(end -0.7874 -0.4064)
			(stroke
				(width 0.1524)
				(type default)
			)
			(layer "F.SilkS")
		)
		(fp_line
			(start -0.12065 -0.305054)
			(end -0.12065 -0.2794)
			(stroke
				(width 0.1)
				(type default)
			)
			(layer "F.Fab")
		)
		(fp_line
			(start -0.67945 -0.305054)
			(end -0.12065 -0.305054)
			(stroke
				(width 0.1)
				(type default)
			)
			(layer "F.Fab")
		)
		(fp_line
			(start 0.67945 -0.3048)
			(end 0.67945 0.3048)
			(stroke
				(width 0.1)
				(type default)
			)
			(layer "F.Fab")
		)
		(fp_line
			(start 0.12065 -0.3048)
			(end 0.67945 -0.3048)
			(stroke
				(width 0.1)
				(type default)
			)
			(layer "F.Fab")
		)
		(fp_line
			(start 0.12065 -0.2794)
			(end 0.12065 -0.3048)
			(stroke
				(width 0.1)
				(type default)
			)
			(layer "F.Fab")
		)
		(fp_line
			(start -0.12065 -0.2794)
			(end 0.12065 -0.2794)
			(stroke
				(width 0.1)
				(type default)
			)
			(layer "F.Fab")
		)
		(fp_line
			(start 0.120396 0.2794)
			(end -0.12065 0.2794)
			(stroke
				(width 0.1)
				(type default)
			)
			(layer "F.Fab")
		)
		(fp_line
			(start -0.12065 0.2794)
			(end -0.12065 0.3048)
			(stroke
				(width 0.1)
				(type default)
			)
			(layer "F.Fab")
		)
		(fp_line
			(start 0.67945 0.3048)
			(end 0.120396 0.3048)
			(stroke
				(width 0.1)
				(type default)
			)
			(layer "F.Fab")
		)
		(fp_line
			(start 0.120396 0.3048)
			(end 0.120396 0.2794)
			(stroke
				(width 0.1)
				(type default)
			)
			(layer "F.Fab")
		)
		(fp_line
			(start -0.12065 0.3048)
			(end -0.67945 0.3048)
			(stroke
				(width 0.1)
				(type default)
			)
			(layer "F.Fab")
		)
		(fp_line
			(start -0.67945 0.3048)
			(end -0.67945 -0.305054)
			(stroke
				(width 0.1)
				(type default)
			)
			(layer "F.Fab")
		)
		(pad "1" smd circle
			(at -0.40005 0 90)
			(size 0 0)
			(layers "F.Cu" "F.Mask" "F.Paste")
			(net "PVCCD_HV_CPU1_LSET1")
		)
		(pad "2" smd circle
			(at 0.40005 0 90)
			(size 0 0)
			(layers "F.Cu" "F.Mask" "F.Paste")
			(net "GND")
		)
	)
)
